(kicad_pcb
	(version 20241229)
	(generator "pcbnew")
	(generator_version "9.0")
	(general
		(thickness 1.599998)
		(legacy_teardrops no)
	)
	(paper "A4")
	(title_block
		(title "Artix - Datacenter Secure Control Module (DC-SCM)")
		(date "2024-11-06")
		(rev "1.1.3")
		(comment 9 "footprints 57-61 of 544")
	)
	(layers
		(0 "F.Cu" signal)
		(4 "In1.Cu" signal)
		(6 "In2.Cu" signal)
		(8 "In3.Cu" signal)
		(10 "In4.Cu" signal)
		(12 "In5.Cu" signal)
		(14 "In6.Cu" signal)
		(2 "B.Cu" signal)
		(9 "F.Adhes" user "F.Adhesive")
		(11 "B.Adhes" user "B.Adhesive")
		(13 "F.Paste" user)
		(15 "B.Paste" user)
		(5 "F.SilkS" user "F.Silkscreen")
		(7 "B.SilkS" user "B.Silkscreen")
		(1 "F.Mask" user)
		(3 "B.Mask" user)
		(17 "Dwgs.User" user "User.Drawings")
		(19 "Cmts.User" user "User.Comments")
		(21 "Eco1.User" user "User.Eco1")
		(23 "Eco2.User" user "User.Eco2")
		(25 "Edge.Cuts" user)
		(27 "Margin" user)
		(31 "F.CrtYd" user "F.Courtyard")
		(29 "B.CrtYd" user "B.Courtyard")
		(35 "F.Fab" user)
		(33 "B.Fab" user)
	)
	(footprint "antmicro-footprints:R_0402_1005Metric"
		(layer "F.Cu")
		(at 90.555 89.235 -90)
		(descr "Resistor SMD 0402")
		(tags "resistor SMD 0402")
		(property "Reference" "R79"
			(at -2.935 -0.345 90)
			(layer "F.SilkS")
			(effects
				(font
					(size 0.7 0.7)
					(thickness 0.15)
				)
				(justify right bottom)
			)
		)
		(property "Value" "R_124k_0402"
			(at 0 1.4 90)
			(layer "F.Fab")
			(effects
				(font
					(size 0.7 0.7)
					(thickness 0.15)
				)
				(justify right bottom)
			)
		)
		(property "Datasheet" "https://www.bourns.com/docs/product-datasheets/cr.pdf"
			(at 0 0 270)
			(layer "F.Fab")
			(hide yes)
			(effects
				(font
					(size 1.27 1.27)
					(thickness 0.15)
				)
			)
		)
		(property "Description" "SMD Chip Resistor, 124 kohm, ± 1%, 100 mW, 0402 [1005 Metric], Thick Film, Precision"
			(at 0 0 270)
			(layer "F.Fab")
			(hide yes)
			(effects
				(font
					(size 1.27 1.27)
					(thickness 0.15)
				)
			)
		)
		(property "Author" "Antmicro"
			(at 1.32 179.79 0)
			(layer "F.Fab")
			(hide yes)
			(effects
				(font
					(size 1 1)
					(thickness 0.15)
				)
			)
		)
		(property "License" "Apache-2.0"
			(at 1.32 179.79 0)
			(layer "F.Fab")
			(hide yes)
			(effects
				(font
					(size 1 1)
					(thickness 0.15)
				)
			)
		)
		(property "MPN" "CR0402-FX-1243GLF"
			(at 1.32 179.79 0)
			(layer "F.Fab")
			(hide yes)
			(effects
				(font
					(size 1 1)
					(thickness 0.15)
				)
			)
		)
		(property "Manufacturer" "Bourns"
			(at 1.32 179.79 0)
			(layer "F.Fab")
			(hide yes)
			(effects
				(font
					(size 1 1)
					(thickness 0.15)
				)
			)
		)
		(property "Tolerance" "1%"
			(at 1.32 179.79 0)
			(layer "F.Fab")
			(hide yes)
			(effects
				(font
					(size 1 1)
					(thickness 0.15)
				)
			)
		)
		(property "Val" "124k"
			(at 1.32 179.79 0)
			(layer "F.Fab")
			(hide yes)
			(effects
				(font
					(size 1 1)
					(thickness 0.15)
				)
			)
		)
		(sheetname "/Power supply/")
		(sheetfile "power-supply.kicad_sch")
		(attr smd)
		(fp_rect
			(start -0.925 -0.47)
			(end 0.925 0.47)
			(stroke
				(width 0.05)
				(type default)
			)
			(fill no)
			(layer "F.CrtYd")
		)
		(fp_rect
			(start -0.5 -0.25)
			(end 0.5 0.25)
			(stroke
				(width 0.15)
				(type solid)
			)
			(fill no)
			(layer "F.Fab")
		)
		(pad "1" smd roundrect
			(at -0.48 0 270)
			(size 0.59 0.64)
			(layers "F.Cu" "F.Mask" "F.Paste")
			(roundrect_rratio 0.25)
			(net 277 "Net-(C82-Pad2)")
			(pintype "passive")
		)
		(pad "2" smd roundrect
			(at 0.48 0 270)
			(size 0.59 0.64)
			(layers "F.Cu" "F.Mask" "F.Paste")
			(roundrect_rratio 0.25)
			(net 196 "Net-(U13-FB)")
			(pintype "passive")
		)
	)
	(footprint "antmicro-footprints:C_0402_1005Metric"
		(layer "F.Cu")
		(at 91.555 89.235 90)
		(descr "Capacitor SMD 0402")
		(tags "capacitor SMD 0402")
		(property "Reference" "C82"
			(at 0.835 0.345 90)
			(layer "F.SilkS")
			(effects
				(font
					(size 0.7 0.7)
					(thickness 0.15)
				)
				(justify left bottom)
			)
		)
		(property "Value" "C_120p_0402"
			(at 0 1.4 90)
			(layer "F.Fab")
			(effects
				(font
					(size 0.7 0.7)
					(thickness 0.15)
				)
				(justify left bottom)
			)
		)
		(property "Datasheet" "https://www.kemet.com/en/us/capacitors/product/C0402C121J5GACTU.html"
			(at 0 0 90)
			(layer "F.Fab")
			(hide yes)
			(effects
				(font
					(size 1.27 1.27)
					(thickness 0.15)
				)
			)
		)
		(property "Description" "120 pF ±2% 100V Ceramic Capacitor C0G, NP0 0402 (1005 Metric)"
			(at 0 0 90)
			(layer "F.Fab")
			(hide yes)
			(effects
				(font
					(size 1.27 1.27)
					(thickness 0.15)
				)
			)
		)
		(property "Author" "Antmicro"
			(at 180.79 -2.32 0)
			(layer "F.Fab")
			(hide yes)
			(effects
				(font
					(size 1 1)
					(thickness 0.15)
				)
			)
		)
		(property "Dielectric" "C0G"
			(at 180.79 -2.32 0)
			(layer "F.Fab")
			(hide yes)
			(effects
				(font
					(size 1 1)
					(thickness 0.15)
				)
			)
		)
		(property "License" "Apache-2.0"
			(at 180.79 -2.32 0)
			(layer "F.Fab")
			(hide yes)
			(effects
				(font
					(size 1 1)
					(thickness 0.15)
				)
			)
		)
		(property "MPN" "C0402C121J5GACTU"
			(at 180.79 -2.32 0)
			(layer "F.Fab")
			(hide yes)
			(effects
				(font
					(size 1 1)
					(thickness 0.15)
				)
			)
		)
		(property "Manufacturer" "KEMET"
			(at 180.79 -2.32 0)
			(layer "F.Fab")
			(hide yes)
			(effects
				(font
					(size 1 1)
					(thickness 0.15)
				)
			)
		)
		(property "Val" "120p"
			(at 180.79 -2.32 0)
			(layer "F.Fab")
			(hide yes)
			(effects
				(font
					(size 1 1)
					(thickness 0.15)
				)
			)
		)
		(property "Voltage" "100V"
			(at 180.79 -2.32 0)
			(layer "F.Fab")
			(hide yes)
			(effects
				(font
					(size 1 1)
					(thickness 0.15)
				)
			)
		)
		(sheetname "/Power supply/")
		(sheetfile "power-supply.kicad_sch")
		(attr smd)
		(fp_rect
			(start -0.925 -0.47)
			(end 0.925 0.47)
			(stroke
				(width 0.05)
				(type default)
			)
			(fill no)
			(layer "F.CrtYd")
		)
		(fp_line
			(start 0.504 -0.25)
			(end 0.504 0.248)
			(stroke
				(width 0.15)
				(type solid)
			)
			(layer "F.Fab")
		)
		(fp_line
			(start -0.494 -0.25)
			(end 0.504 -0.25)
			(stroke
				(width 0.15)
				(type solid)
			)
			(layer "F.Fab")
		)
		(fp_line
			(start 0.504 0.248)
			(end -0.494 0.248)
			(stroke
				(width 0.15)
				(type solid)
			)
			(layer "F.Fab")
		)
		(fp_line
			(start -0.494 0.248)
			(end -0.494 -0.25)
			(stroke
				(width 0.15)
				(type solid)
			)
			(layer "F.Fab")
		)
		(pad "1" smd roundrect
			(at -0.48 0 90)
			(size 0.59 0.64)
			(layers "F.Cu" "F.Mask" "F.Paste")
			(roundrect_rratio 0.25)
			(net 196 "Net-(U13-FB)")
			(pintype "passive")
		)
		(pad "2" smd roundrect
			(at 0.48 0 90)
			(size 0.59 0.64)
			(layers "F.Cu" "F.Mask" "F.Paste")
			(roundrect_rratio 0.25)
			(net 277 "Net-(C82-Pad2)")
			(pintype "passive")
		)
	)
	(footprint "antmicro-footprints:R_0402_1005Metric"
		(layer "F.Cu")
		(at 89.555 89.235 90)
		(descr "Resistor SMD 0402")
		(tags "resistor SMD 0402")
		(property "Reference" "R80"
			(at 0.735 0.345 90)
			(layer "F.SilkS")
			(effects
				(font
					(size 0.7 0.7)
					(thickness 0.15)
				)
				(justify left bottom)
			)
		)
		(property "Value" "R_100k_0402"
			(at 0 1.4 90)
			(layer "F.Fab")
			(effects
				(font
					(size 0.7 0.7)
					(thickness 0.15)
				)
				(justify left bottom)
			)
		)
		(property "Datasheet" "https://www.bourns.com/docs/product-datasheets/cr.pdf"
			(at 0 0 90)
			(layer "F.Fab")
			(hide yes)
			(effects
				(font
					(size 1.27 1.27)
					(thickness 0.15)
				)
			)
		)
		(property "Description" "SMD Chip Resistor, 100 kohm, ± 1%, 62.5 mW, 0402 [1005 Metric], Thick Film, General Purpose"
			(at 0 0 90)
			(layer "F.Fab")
			(hide yes)
			(effects
				(font
					(size 1.27 1.27)
					(thickness 0.15)
				)
			)
		)
		(property "Author" "Antmicro"
			(at 178.79 -0.32 0)
			(layer "F.Fab")
			(hide yes)
			(effects
				(font
					(size 1 1)
					(thickness 0.15)
				)
			)
		)
		(property "License" "Apache-2.0"
			(at 178.79 -0.32 0)
			(layer "F.Fab")
			(hide yes)
			(effects
				(font
					(size 1 1)
					(thickness 0.15)
				)
			)
		)
		(property "MPN" "CR0402-FX-1003GLF"
			(at 178.79 -0.32 0)
			(layer "F.Fab")
			(hide yes)
			(effects
				(font
					(size 1 1)
					(thickness 0.15)
				)
			)
		)
		(property "Manufacturer" "Bourns"
			(at 178.79 -0.32 0)
			(layer "F.Fab")
			(hide yes)
			(effects
				(font
					(size 1 1)
					(thickness 0.15)
				)
			)
		)
		(property "Tolerance" "1%"
			(at 178.79 -0.32 0)
			(layer "F.Fab")
			(hide yes)
			(effects
				(font
					(size 1 1)
					(thickness 0.15)
				)
			)
		)
		(property "Val" "100k"
			(at 178.79 -0.32 0)
			(layer "F.Fab")
			(hide yes)
			(effects
				(font
					(size 1 1)
					(thickness 0.15)
				)
			)
		)
		(sheetname "/Power supply/")
		(sheetfile "power-supply.kicad_sch")
		(attr smd)
		(fp_rect
			(start -0.925 -0.47)
			(end 0.925 0.47)
			(stroke
				(width 0.05)
				(type default)
			)
			(fill no)
			(layer "F.CrtYd")
		)
		(fp_rect
			(start -0.5 -0.25)
			(end 0.5 0.25)
			(stroke
				(width 0.15)
				(type solid)
			)
			(fill no)
			(layer "F.Fab")
		)
		(pad "1" smd roundrect
			(at -0.48 0 90)
			(size 0.59 0.64)
			(layers "F.Cu" "F.Mask" "F.Paste")
			(roundrect_rratio 0.25)
			(net 196 "Net-(U13-FB)")
			(pintype "passive")
		)
		(pad "2" smd roundrect
			(at 0.48 0 90)
			(size 0.59 0.64)
			(layers "F.Cu" "F.Mask" "F.Paste")
			(roundrect_rratio 0.25)
			(net 1 "GND")
			(pintype "passive")
		)
	)
	(footprint "antmicro-footprints:VSSOP-8_3x3mm_P0.65mm"
		(layer "F.Cu")
		(at 69.716 92.801143 -90)
		(property "Reference" "U9"
			(at -0.791143 1.976 90)
			(layer "F.SilkS")
			(effects
				(font
					(size 0.7 0.7)
					(thickness 0.15)
				)
				(justify right bottom)
			)
		)
		(property "Value" "LM3881"
			(at -2.15 3.971 90)
			(layer "F.Fab")
			(effects
				(font
					(size 0.7 0.7)
					(thickness 0.15)
				)
				(justify right bottom)
			)
		)
		(property "Datasheet" "http://www.ti.com/lit/ds/symlink/lm3881.pdf"
			(at 0 0 270)
			(layer "F.Fab")
			(hide yes)
			(effects
				(font
					(size 1.27 1.27)
					(thickness 0.15)
				)
			)
		)
		(property "Description" "Power Sequencer, 3-Monitors, 2.7V-5.5Vin,VSSOP-8"
			(at 0 0 270)
			(layer "F.Fab")
			(hide yes)
			(effects
				(font
					(size 1.27 1.27)
					(thickness 0.15)
				)
			)
		)
		(property "Author" "Antmicro"
			(at -23.085143 162.517143 0)
			(layer "F.Fab")
			(hide yes)
			(effects
				(font
					(size 1 1)
					(thickness 0.15)
				)
			)
		)
		(property "License" "Apache-2.0"
			(at -23.085143 162.517143 0)
			(layer "F.Fab")
			(hide yes)
			(effects
				(font
					(size 1 1)
					(thickness 0.15)
				)
			)
		)
		(property "MPN" "LM3881MME/NOPB"
			(at -23.085143 162.517143 0)
			(layer "F.Fab")
			(hide yes)
			(effects
				(font
					(size 1 1)
					(thickness 0.15)
				)
			)
		)
		(property "Manufacturer" "Texas Instruments"
			(at -23.085143 162.517143 0)
			(layer "F.Fab")
			(hide yes)
			(effects
				(font
					(size 1 1)
					(thickness 0.15)
				)
			)
		)
		(sheetname "/Power supply/")
		(sheetfile "power-supply.kicad_sch")
		(attr smd)
		(fp_line
			(start -1.496 1.625)
			(end 1.554 1.625)
			(stroke
				(width 0.12)
				(type solid)
			)
			(layer "F.SilkS")
		)
		(fp_line
			(start -1.6 -1.625)
			(end 1.554 -1.625)
			(stroke
				(width 0.12)
				(type solid)
			)
			(layer "F.SilkS")
		)
		(fp_circle
			(center -2.1 -1.438)
			(end -2.05 -1.438)
			(stroke
				(width 0.12)
				(type solid)
			)
			(fill yes)
			(layer "F.SilkS")
		)
		(fp_rect
			(start -3 -1.838)
			(end 3 1.862)
			(stroke
				(width 0.05)
				(type solid)
			)
			(fill no)
			(layer "F.CrtYd")
		)
		(fp_line
			(start -1.497 1.5)
			(end -1.497 -1.502)
			(stroke
				(width 0.15)
				(type solid)
			)
			(layer "F.Fab")
		)
		(fp_line
			(start 1.504 1.5)
			(end -1.497 1.5)
			(stroke
				(width 0.15)
				(type solid)
			)
			(layer "F.Fab")
		)
		(fp_line
			(start -1.497 -1.502)
			(end 1.504 -1.502)
			(stroke
				(width 0.15)
				(type solid)
			)
			(layer "F.Fab")
		)
		(fp_line
			(start 1.504 -1.502)
			(end 1.504 1.5)
			(stroke
				(width 0.15)
				(type solid)
			)
			(layer "F.Fab")
		)
		(pad "1" smd rect
			(at -2.096 -0.975 270)
			(size 1.556504 0.457986)
			(layers "F.Cu" "F.Mask" "F.Paste")
			(net 4 "VCC5V0")
			(pinfunction "VCC")
			(pintype "power_in")
		)
		(pad "2" smd roundrect
			(at -2.096 -0.326 270)
			(size 1.556504 0.457986)
			(layers "F.Cu" "F.Mask" "F.Paste")
			(roundrect_rratio 0.5)
			(net 573 "/Power supply/5V0_PG")
			(pinfunction "EN")
			(pintype "passive")
		)
		(pad "3" smd roundrect
			(at -2.096 0.325 270)
			(size 1.556504 0.457986)
			(layers "F.Cu" "F.Mask" "F.Paste")
			(roundrect_rratio 0.5)
			(net 1 "GND")
			(pinfunction "GND")
			(pintype "power_in")
		)
		(pad "4" smd roundrect
			(at -2.096 0.974 270)
			(size 1.556504 0.457986)
			(layers "F.Cu" "F.Mask" "F.Paste")
			(roundrect_rratio 0.5)
			(net 4 "VCC5V0")
			(pinfunction "INV")
			(pintype "input")
		)
		(pad "5" smd roundrect
			(at 2.105 0.974 270)
			(size 1.556504 0.457986)
			(layers "F.Cu" "F.Mask" "F.Paste")
			(roundrect_rratio 0.5)
			(net 103 "Net-(U9-TADJ)")
			(pinfunction "TADJ")
			(pintype "passive")
		)
		(pad "6" smd roundrect
			(at 2.105 0.325 270)
			(size 1.556504 0.457986)
			(layers "F.Cu" "F.Mask" "F.Paste")
			(roundrect_rratio 0.5)
			(net 297 "/Power supply/VCCIO_EN")
			(pinfunction "FLAG3")
			(pintype "open_collector")
		)
		(pad "7" smd roundrect
			(at 2.105 -0.326 270)
			(size 1.556504 0.457986)
			(layers "F.Cu" "F.Mask" "F.Paste")
			(roundrect_rratio 0.5)
			(net 296 "/Power supply/VCCAUX_EN")
			(pinfunction "FLAG2")
			(pintype "open_collector")
		)
		(pad "8" smd roundrect
			(at 2.105 -0.975 270)
			(size 1.556504 0.457986)
			(layers "F.Cu" "F.Mask" "F.Paste")
			(roundrect_rratio 0.5)
			(net 295 "/Power supply/VCCINT_EN")
			(pinfunction "FLAG1")
			(pintype "open_collector")
		)
	)
	(footprint "antmicro-footprints:C_0402_1005Metric"
		(layer "F.Cu")
		(at 94.674 140.075 -90)
		(descr "Capacitor SMD 0402")
		(tags "capacitor SMD 0402")
		(property "Reference" "C49"
			(at -2.975 -0.326 90)
			(layer "F.SilkS")
			(effects
				(font
					(size 0.7 0.7)
					(thickness 0.15)
				)
				(justify right bottom)
			)
		)
		(property "Value" "C_470n_0402"
			(at 0 1.4 90)
			(layer "F.Fab")
			(effects
				(font
					(size 0.7 0.7)
					(thickness 0.15)
				)
				(justify right bottom)
			)
		)
		(property "Datasheet" "https://product.tdk.com/en/search/capacitor/ceramic/mlcc/info?part_no=C1005X5R1E474M050BB"
			(at 0 0 270)
			(layer "F.Fab")
			(hide yes)
			(effects
				(font
					(size 1.27 1.27)
					(thickness 0.15)
				)
			)
		)
		(property "Description" "SMD Multilayer Ceramic Capacitor, 0.47 µF, 25 V, 0402 [1005 Metric], ± 20%, X5R, C"
			(at 0 0 270)
			(layer "F.Fab")
			(hide yes)
			(effects
				(font
					(size 1.27 1.27)
					(thickness 0.15)
				)
			)
		)
		(property "Author" "Antmicro"
			(at -45.401 234.749 0)
			(layer "F.Fab")
			(hide yes)
			(effects
				(font
					(size 1 1)
					(thickness 0.15)
				)
			)
		)
		(property "Dielectric" ""
			(at -45.401 234.749 0)
			(layer "F.Fab")
			(hide yes)
			(effects
				(font
					(size 1 1)
					(thickness 0.15)
				)
			)
		)
		(property "License" "Apache-2.0"
			(at -45.401 234.749 0)
			(layer "F.Fab")
			(hide yes)
			(effects
				(font
					(size 1 1)
					(thickness 0.15)
				)
			)
		)
		(property "MPN" "C1005X5R1E474M050BB"
			(at -45.401 234.749 0)
			(layer "F.Fab")
			(hide yes)
			(effects
				(font
					(size 1 1)
					(thickness 0.15)
				)
			)
		)
		(property "Manufacturer" "TDK"
			(at -45.401 234.749 0)
			(layer "F.Fab")
			(hide yes)
			(effects
				(font
					(size 1 1)
					(thickness 0.15)
				)
			)
		)
		(property "Val" "470n"
			(at -45.401 234.749 0)
			(layer "F.Fab")
			(hide yes)
			(effects
				(font
					(size 1 1)
					(thickness 0.15)
				)
			)
		)
		(property "Voltage" ""
			(at -45.401 234.749 0)
			(layer "F.Fab")
			(hide yes)
			(effects
				(font
					(size 1 1)
					(thickness 0.15)
				)
			)
		)
		(sheetname "/DDR3/")
		(sheetfile "ddr3.kicad_sch")
		(attr smd)
		(fp_rect
			(start -0.925 -0.47)
			(end 0.925 0.47)
			(stroke
				(width 0.05)
				(type default)
			)
			(fill no)
			(layer "F.CrtYd")
		)
		(fp_line
			(start -0.494 0.248)
			(end -0.494 -0.25)
			(stroke
				(width 0.15)
				(type solid)
			)
			(layer "F.Fab")
		)
		(fp_line
			(start 0.504 0.248)
			(end -0.494 0.248)
			(stroke
				(width 0.15)
				(type solid)
			)
			(layer "F.Fab")
		)
		(fp_line
			(start -0.494 -0.25)
			(end 0.504 -0.25)
			(stroke
				(width 0.15)
				(type solid)
			)
			(layer "F.Fab")
		)
		(fp_line
			(start 0.504 -0.25)
			(end 0.504 0.248)
			(stroke
				(width 0.15)
				(type solid)
			)
			(layer "F.Fab")
		)
		(pad "1" smd roundrect
			(at -0.48 0 270)
			(size 0.59 0.64)
			(layers "F.Cu" "F.Mask" "F.Paste")
			(roundrect_rratio 0.25)
			(net 1 "GND")
			(pintype "passive")
		)
		(pad "2" smd roundrect
			(at 0.48 0 270)
			(size 0.59 0.64)
			(layers "F.Cu" "F.Mask" "F.Paste")
			(roundrect_rratio 0.25)
			(net 3 "VCC1V35")
			(pintype "passive")
		)
	)
)
